(kicad_pcb
	(version 20260206)
	(generator "pcbnew")
	(generator_version "10.0")
	(general
		(thickness 1.6)
		(legacy_teardrops no)
	)
	(paper "A4")
	(title_block
		(title "Bryce Canyon_LED_16347-1_OCP.brd")
		(comment 1 "Bryce Canyon / footprints 21-23 of 49")
	)
	(layers
		(0 "F.Cu" signal "TOP")
		(2 "B.Cu" signal "BOTTOM")
		(9 "F.Adhes" user "F.Adhesive")
		(11 "B.Adhes" user "B.Adhesive")
		(13 "F.Paste" user "Package Geometry/Pastemask Top")
		(15 "B.Paste" user "Package Geometry/Pastemask Bottom")
		(5 "F.SilkS" user "Ref Des/Silkscreen Top")
		(7 "B.SilkS" user "Ref Des/Silkscreen Bottom")
		(1 "F.Mask" user "Board Geometry/Soldermask Top")
		(3 "B.Mask" user "Board Geometry/Soldermask Bottom")
		(17 "Dwgs.User" user "User.Drawings")
		(19 "Cmts.User" user "User.Comments")
		(21 "Eco1.User" user "User.Eco1")
		(23 "Eco2.User" user "User.Eco2")
		(25 "Edge.Cuts" user "Board Geometry/Outline")
		(27 "Margin" user)
		(31 "F.CrtYd" user "Package Geometry/Place Bound Top")
		(29 "B.CrtYd" user "Package Geometry/Place Bound Bottom")
		(35 "F.Fab" user "Ref Des/Assembly Top")
		(33 "B.Fab" user "Ref Des/Assembly Bottom")
	)
	(footprint ""
		(layer "B.Cu")
		(at 38.481 -4.953 -90)
		(property "Reference" "C2"
			(at 0 0 90)
			(layer "B.SilkS")
			(hide yes)
			(effects
				(font
					(size 1.27 1.27)
				)
				(justify mirror)
			)
		)
		(property "Value" "SC10U16V6KX-2GP"
			(at 0.0762 -5.1308 270)
			(unlocked yes)
			(layer "B.Fab")
			(hide yes)
			(effects
				(font
					(size 1.016 1.016)
					(thickness 0.1524)
				)
				(justify mirror)
			)
		)
		(property "Device Type" "C1206H71"
			(at 0.127 -6.6548 270)
			(unlocked yes)
			(layer "B.Fab")
			(hide yes)
			(effects
				(font
					(size 1.016 1.016)
					(thickness 0.1524)
				)
				(justify mirror)
			)
		)
		(duplicate_pad_numbers_are_jumpers no)
		(fp_line
			(start -1.016 2.2352)
			(end 1.016 2.2352)
			(stroke
				(width 0.1524)
				(type default)
			)
			(layer "B.SilkS")
		)
		(fp_line
			(start 1.016 2.2352)
			(end 1.016 0.8382)
			(stroke
				(width 0.1524)
				(type default)
			)
			(layer "B.SilkS")
		)
		(fp_line
			(start -1.016 0.8382)
			(end -1.016 2.2352)
			(stroke
				(width 0.1524)
				(type default)
			)
			(layer "B.SilkS")
		)
		(fp_line
			(start 1.016 -0.8382)
			(end 1.016 -2.2352)
			(stroke
				(width 0.1524)
				(type default)
			)
			(layer "B.SilkS")
		)
		(fp_line
			(start -1.016 -2.2352)
			(end -1.016 -0.8382)
			(stroke
				(width 0.1524)
				(type default)
			)
			(layer "B.SilkS")
		)
		(fp_line
			(start 1.016 -2.2352)
			(end -1.016 -2.2352)
			(stroke
				(width 0.1524)
				(type default)
			)
			(layer "B.SilkS")
		)
		(fp_rect
			(start 1.0922 2.3114)
			(end -1.0922 -2.3114)
			(stroke
				(width 0)
				(type default)
			)
			(fill no)
			(layer "B.CrtYd")
		)
		(fp_poly
			(pts
				(xy -1.0922 -2.3114) (xy -1.0922 2.3114) (xy 1.0922 2.3114) (xy 1.0922 -2.3114)
			)
			(stroke
				(width 0)
				(type default)
			)
			(fill no)
			(layer "B.Fab")
		)
		(pad "1" smd rect
			(at 0 -1.397 90)
			(size 1.651 1.27)
			(layers "B.Cu" "B.Mask" "B.Paste")
			(net "P5V_A")
		)
		(pad "2" smd rect
			(at 0 1.397 90)
			(size 1.651 1.27)
			(layers "B.Cu" "B.Mask" "B.Paste")
			(net "GND")
		)
	)
	(footprint ""
		(layer "B.Cu")
		(at 49.150016 -11.8999)
		(property "Reference" "CN1"
			(at 0 0 0)
			(layer "B.SilkS")
			(hide yes)
			(effects
				(font
					(size 1.27 1.27)
				)
				(justify mirror)
			)
		)
		(property "Value" "AMP-CONN20D-4-GP"
			(at 8.79348 -0.84963 0)
			(unlocked yes)
			(layer "B.Fab")
			(hide yes)
			(effects
				(font
					(size 1.016 1.016)
					(thickness 0.1524)
				)
				(justify mirror)
			)
		)
		(property "Device Type" "G846A20120T1HR"
			(at 8.79348 -2.37363 0)
			(unlocked yes)
			(layer "B.Fab")
			(hide yes)
			(effects
				(font
					(size 1.016 1.016)
					(thickness 0.1524)
				)
				(justify mirror)
			)
		)
		(duplicate_pad_numbers_are_jumpers no)
		(fp_line
			(start -7.5057 0.254)
			(end -7.5057 2.8194)
			(stroke
				(width 0.1524)
				(type default)
			)
			(layer "B.SilkS")
		)
		(fp_line
			(start -7.5057 2.8194)
			(end -5.0546 2.8194)
			(stroke
				(width 0.1524)
				(type default)
			)
			(layer "B.SilkS")
		)
		(fp_line
			(start -6.5532 -2.5527)
			(end -6.5532 0.254)
			(stroke
				(width 0.1524)
				(type default)
			)
			(layer "B.SilkS")
		)
		(fp_line
			(start -6.5532 0.254)
			(end -7.5057 0.254)
			(stroke
				(width 0.1524)
				(type default)
			)
			(layer "B.SilkS")
		)
		(fp_line
			(start -5.0546 -4.064)
			(end -5.0546 -2.5527)
			(stroke
				(width 0.1524)
				(type default)
			)
			(layer "B.SilkS")
		)
		(fp_line
			(start -5.0546 -2.5527)
			(end -6.5532 -2.5527)
			(stroke
				(width 0.1524)
				(type default)
			)
			(layer "B.SilkS")
		)
		(fp_line
			(start -5.0546 2.8194)
			(end -5.0546 4.064)
			(stroke
				(width 0.1524)
				(type default)
			)
			(layer "B.SilkS")
		)
		(fp_line
			(start -5.0546 4.064)
			(end 5.0546 4.064)
			(stroke
				(width 0.1524)
				(type default)
			)
			(layer "B.SilkS")
		)
		(fp_line
			(start 4.0386 -4.1529)
			(end 5.1435 -4.1529)
			(stroke
				(width 0.3302)
				(type default)
			)
			(layer "B.SilkS")
		)
		(fp_line
			(start 5.0546 -4.064)
			(end -5.0546 -4.064)
			(stroke
				(width 0.1524)
				(type default)
			)
			(layer "B.SilkS")
		)
		(fp_line
			(start 5.0546 -2.5527)
			(end 5.0546 -4.064)
			(stroke
				(width 0.1524)
				(type default)
			)
			(layer "B.SilkS")
		)
		(fp_line
			(start 5.0546 2.8194)
			(end 7.5057 2.8194)
			(stroke
				(width 0.1524)
				(type default)
			)
			(layer "B.SilkS")
		)
		(fp_line
			(start 5.0546 4.064)
			(end 5.0546 2.8194)
			(stroke
				(width 0.1524)
				(type default)
			)
			(layer "B.SilkS")
		)
		(fp_line
			(start 5.1435 -4.1529)
			(end 5.1435 -3.1877)
			(stroke
				(width 0.3302)
				(type default)
			)
			(layer "B.SilkS")
		)
		(fp_line
			(start 6.5532 -2.5527)
			(end 5.0546 -2.5527)
			(stroke
				(width 0.1524)
				(type default)
			)
			(layer "B.SilkS")
		)
		(fp_line
			(start 6.5532 0.254)
			(end 6.5532 -2.5527)
			(stroke
				(width 0.1524)
				(type default)
			)
			(layer "B.SilkS")
		)
		(fp_line
			(start 7.5057 0.254)
			(end 6.5532 0.254)
			(stroke
				(width 0.1524)
				(type default)
			)
			(layer "B.SilkS")
		)
		(fp_line
			(start 7.5057 2.8194)
			(end 7.5057 0.254)
			(stroke
				(width 0.1524)
				(type default)
			)
			(layer "B.SilkS")
		)
		(fp_rect
			(start 4.804918 2.097532)
			(end -4.804918 -2.097532)
			(stroke
				(width 0)
				(type default)
			)
			(fill yes)
			(layer "B.SilkS")
		)
		(fp_poly
			(pts
				(xy 4.500118 -4.1402) (xy 3.865118 -4.7752) (xy 5.135118 -4.7752)
			)
			(stroke
				(width 0)
				(type default)
			)
			(fill yes)
			(layer "B.SilkS")
		)
		(fp_poly
			(pts
				(xy 4.8006 3.302) (xy 4.8006 2.2987) (xy 6.9469 2.2987) (xy 6.9469 0.508) (xy 6.2992 0.508) (xy 6.2992 -2.2987)
				(xy 4.8006 -2.2987) (xy 4.8006 -3.302) (xy -4.8006 -3.302) (xy -4.8006 -2.2987) (xy -6.2992 -2.2987)
				(xy -6.2992 0.508) (xy -6.9469 0.508) (xy -6.9469 2.2987) (xy -4.8006 2.2987) (xy -4.8006 3.302)
			)
			(stroke
				(width 0)
				(type default)
			)
			(fill no)
			(layer "B.CrtYd")
		)
		(fp_poly
			(pts
				(xy 5.3086 4.318) (xy 5.3086 3.0734) (xy 7.7597 3.0734) (xy 7.7597 0) (xy 6.8072 0) (xy 6.8072 -2.8067)
				(xy 5.3086 -2.8067) (xy 5.3086 -4.318) (xy -5.3086 -4.318) (xy -5.3086 -2.8067) (xy -6.8072 -2.8067)
				(xy -6.8072 -0.00635) (xy -6.2992 -0.00635) (xy -6.2992 -2.2987) (xy -4.8006 -2.2987) (xy -4.8006 -3.302)
				(xy 4.8006 -3.302) (xy 4.8006 -2.2987) (xy 6.2992 -2.2987) (xy 6.2992 0.508) (xy 6.9469 0.508) (xy 6.9469 2.2987)
				(xy 4.8006 2.2987) (xy 4.8006 3.302) (xy -4.8006 3.302) (xy -4.8006 2.2987) (xy -6.9469 2.2987)
				(xy -6.9469 0.508) (xy -6.2992 0.508) (xy -6.2992 0.00635) (xy -7.7597 0.00635) (xy -7.7597 3.0734)
				(xy -5.3086 3.0734) (xy -5.3086 4.318)
			)
			(stroke
				(width 0)
				(type default)
			)
			(fill no)
			(layer "B.CrtYd")
		)
		(fp_poly
			(pts
				(xy 5.3086 4.318) (xy 5.3086 3.0734) (xy 7.7597 3.0734) (xy 7.7597 0) (xy 6.8072 0) (xy 6.8072 -2.8067)
				(xy 5.3086 -2.8067) (xy 5.3086 -4.318) (xy -5.3086 -4.318) (xy -5.3086 -2.8067) (xy -6.8072 -2.8067)
				(xy -6.8072 0) (xy -7.7597 0) (xy -7.7597 3.0734) (xy -5.3086 3.0734) (xy -5.3086 4.318)
			)
			(stroke
				(width 0)
				(type default)
			)
			(fill no)
			(layer "B.Fab")
		)
		(pad "1" smd rect
			(at 4.500118 -3.050032 180)
			(size 0.6096 1.4986)
			(layers "B.Cu" "B.Mask" "B.Paste")
			(net "DRIVE_A_26_32_FLT_LED")
		)
		(pad "2" smd rect
			(at 4.500118 3.050032 180)
			(size 0.6096 1.4986)
			(layers "B.Cu" "B.Mask" "B.Paste")
			(net "DRIVE_A_27_33_FLT_LED")
		)
		(pad "3" smd rect
			(at 3.50012 -3.050032 180)
			(size 0.6096 1.4986)
			(layers "B.Cu" "B.Mask" "B.Paste")
			(net "DRIVE_A_26_32_ACT")
		)
		(pad "4" smd rect
			(at 3.50012 3.050032 180)
			(size 0.6096 1.4986)
			(layers "B.Cu" "B.Mask" "B.Paste")
			(net "DRIVE_A_27_33_ACT")
		)
		(pad "5" smd rect
			(at 2.500122 -3.050032 180)
			(size 0.6096 1.4986)
			(layers "B.Cu" "B.Mask" "B.Paste")
			(net "Net_23")
		)
		(pad "6" smd rect
			(at 2.500122 3.050032 180)
			(size 0.6096 1.4986)
			(layers "B.Cu" "B.Mask" "B.Paste")
			(net "DRIVE_A_28_34_FLT_LED")
		)
		(pad "7" smd rect
			(at 1.500124 -3.050032 180)
			(size 0.6096 1.4986)
			(layers "B.Cu" "B.Mask" "B.Paste")
			(net "P5V_A")
		)
		(pad "8" smd rect
			(at 1.500124 3.050032 180)
			(size 0.6096 1.4986)
			(layers "B.Cu" "B.Mask" "B.Paste")
			(net "DRIVE_A_28_34_ACT")
		)
		(pad "9" smd rect
			(at 0.500126 -3.050032 180)
			(size 0.6096 1.4986)
			(layers "B.Cu" "B.Mask" "B.Paste")
			(net "P5V_A")
		)
		(pad "10" smd rect
			(at 0.500126 3.050032 180)
			(size 0.6096 1.4986)
			(layers "B.Cu" "B.Mask" "B.Paste")
			(net "DRIVE_A_29_35_FLT_LED")
		)
		(pad "11" smd rect
			(at -0.500126 -3.050032 180)
			(size 0.6096 1.4986)
			(layers "B.Cu" "B.Mask" "B.Paste")
			(net "P5V_A")
		)
		(pad "12" smd rect
			(at -0.500126 3.050032 180)
			(size 0.6096 1.4986)
			(layers "B.Cu" "B.Mask" "B.Paste")
			(net "DRIVE_A_29_35_ACT")
		)
		(pad "13" smd rect
			(at -1.500124 -3.050032 180)
			(size 0.6096 1.4986)
			(layers "B.Cu" "B.Mask" "B.Paste")
			(net "Net_62")
		)
		(pad "14" smd rect
			(at -1.500124 3.050032 180)
			(size 0.6096 1.4986)
			(layers "B.Cu" "B.Mask" "B.Paste")
			(net "DRIVE_A_24_30_FLT_LED")
		)
		(pad "15" smd rect
			(at -2.500122 -3.050032 180)
			(size 0.6096 1.4986)
			(layers "B.Cu" "B.Mask" "B.Paste")
			(net "GND")
		)
		(pad "16" smd rect
			(at -2.500122 3.050032 180)
			(size 0.6096 1.4986)
			(layers "B.Cu" "B.Mask" "B.Paste")
			(net "DRIVE_A_24_30_ACT")
		)
		(pad "17" smd rect
			(at -3.50012 -3.050032 180)
			(size 0.6096 1.4986)
			(layers "B.Cu" "B.Mask" "B.Paste")
			(net "GND")
		)
		(pad "18" smd rect
			(at -3.50012 3.050032 180)
			(size 0.6096 1.4986)
			(layers "B.Cu" "B.Mask" "B.Paste")
			(net "DRIVE_A_25_31_FLT_LED")
		)
		(pad "19" smd rect
			(at -4.500118 -3.050032 180)
			(size 0.6096 1.4986)
			(layers "B.Cu" "B.Mask" "B.Paste")
			(net "GND")
		)
		(pad "20" smd rect
			(at -4.500118 3.050032 180)
			(size 0.6096 1.4986)
			(layers "B.Cu" "B.Mask" "B.Paste")
			(net "DRIVE_A_25_31_ACT")
		)
		(pad "21" smd rect
			(at -6.500114 1.549908 180)
			(size 1.4986 2.0066)
			(layers "B.Cu" "B.Mask" "B.Paste")
			(net "GND")
		)
		(pad "22" smd rect
			(at 6.500114 1.549908 180)
			(size 1.4986 2.0066)
			(layers "B.Cu" "B.Mask" "B.Paste")
			(net "GND")
		)
		(zone
			(layer "B.Cu")
			(hatch none 0.5)
			(connect_pads
				(clearance 0)
			)
			(min_thickness 0.25)
			(keepout
				(tracks allowed)
				(vias not_allowed)
				(pads allowed)
				(copperpour not_allowed)
				(footprints allowed)
			)
			(placement
				(enabled no)
				(sheetname "")
			)
			(fill
				(thermal_gap 0.5)
				(thermal_bridge_width 0.5)
				(island_removal_mode 0)
			)
			(polygon
				(pts
					(xy 53.954934 -13.692632) (xy 44.345098 -13.692632) (xy 44.345098 -14.200632) (xy 53.954934 -14.200632)
				)
			)
		)
		(zone
			(layer "B.Cu")
			(hatch none 0.5)
			(connect_pads
				(clearance 0)
			)
			(min_thickness 0.25)
			(keepout
				(tracks allowed)
				(vias not_allowed)
				(pads allowed)
				(copperpour not_allowed)
				(footprints allowed)
			)
			(placement
				(enabled no)
				(sheetname "")
			)
			(fill
				(thermal_gap 0.5)
				(thermal_bridge_width 0.5)
				(island_removal_mode 0)
			)
			(polygon
				(pts
					(xy 53.954934 -9.599168) (xy 44.345098 -9.599168) (xy 44.345098 -14.200632) (xy 53.954934 -14.200632)
				)
			)
		)
		(zone
			(layer "B.Cu")
			(hatch none 0.5)
			(connect_pads
				(clearance 0)
			)
			(min_thickness 0.25)
			(keepout
				(tracks not_allowed)
				(vias allowed)
				(pads allowed)
				(copperpour not_allowed)
				(footprints allowed)
			)
			(placement
				(enabled no)
				(sheetname "")
			)
			(fill
				(thermal_gap 0.5)
				(thermal_bridge_width 0.5)
				(island_removal_mode 0)
			)
			(polygon
				(pts
					(xy 53.954934 -9.599168) (xy 44.345098 -9.599168) (xy 44.345098 -14.200632) (xy 53.954934 -14.200632)
				)
			)
		)
		(zone
			(layer "B.Cu")
			(hatch none 0.5)
			(connect_pads
				(clearance 0)
			)
			(min_thickness 0.25)
			(keepout
				(tracks allowed)
				(vias not_allowed)
				(pads allowed)
				(copperpour not_allowed)
				(footprints allowed)
			)
			(placement
				(enabled no)
				(sheetname "")
			)
			(fill
				(thermal_gap 0.5)
				(thermal_bridge_width 0.5)
				(island_removal_mode 0)
			)
			(polygon
				(pts
					(xy 53.954934 -9.599168) (xy 44.345098 -9.599168) (xy 44.345098 -10.107168) (xy 53.954934 -10.107168)
				)
			)
		)
	)
	(footprint ""
		(layer "B.Cu")
		(at 110.0074 -5.9182)
		(property "Reference" "Q8"
			(at 0 0 0)
			(layer "B.SilkS")
			(hide yes)
			(effects
				(font
					(size 1.27 1.27)
				)
				(justify mirror)
			)
		)
		(property "Value" "SSM3K324R-GP"
			(at -0.127 -8.9662 0)
			(unlocked yes)
			(layer "B.Fab")
			(hide yes)
			(effects
				(font
					(size 1.016 1.016)
					(thickness 0.1524)
				)
				(justify mirror)
			)
		)
		(property "Device Type" "SOT23DGS2D4H35"
			(at -0.127 -10.4902 0)
			(unlocked yes)
			(layer "B.Fab")
			(hide yes)
			(effects
				(font
					(size 1.016 1.016)
					(thickness 0.1524)
				)
				(justify mirror)
			)
		)
		(duplicate_pad_numbers_are_jumpers no)
		(fp_line
			(start -1.651 -1.778)
			(end 1.651 -1.778)
			(stroke
				(width 0.1524)
				(type default)
			)
			(layer "B.SilkS")
		)
		(fp_line
			(start -1.651 1.778)
			(end -1.651 -1.778)
			(stroke
				(width 0.1524)
				(type default)
			)
			(layer "B.SilkS")
		)
		(fp_line
			(start 1.651 -1.778)
			(end 1.651 1.778)
			(stroke
				(width 0.1524)
				(type default)
			)
			(layer "B.SilkS")
		)
		(fp_line
			(start 1.651 1.778)
			(end -1.651 1.778)
			(stroke
				(width 0.1524)
				(type default)
			)
			(layer "B.SilkS")
		)
		(fp_poly
			(pts
				(xy 1.778 1.8796) (xy 1.778 -1.8796) (xy -1.778 -1.8796) (xy -1.778 1.8796)
			)
			(stroke
				(width 0)
				(type default)
			)
			(fill no)
			(layer "B.CrtYd")
		)
		(fp_poly
			(pts
				(xy 1.778 1.8796) (xy 1.778 -1.8796) (xy -1.778 -1.8796) (xy -1.778 1.8796)
			)
			(stroke
				(width 0)
				(type default)
			)
			(fill no)
			(layer "B.Fab")
		)
		(pad "D" smd custom
			(at 0 -0.9525 180)
			(size 0.1905 0.1905)
			(layers "B.Cu" "B.Mask" "B.Paste")
			(net "DRV_ACT_27_33_N")
			(options
				(clearance outline)
				(anchor circle)
			)
			(primitives
				(gr_poly
					(pts
						(arc
							(start -0.1778 -0.5715)
							(mid -0.321484 -0.511984)
							(end -0.381 -0.3683)
						)
						(arc
							(start -0.381 0.3683)
							(mid -0.321484 0.511984)
							(end -0.1778 0.5715)
						)
						(arc
							(start 0.1778 0.5715)
							(mid 0.321484 0.511984)
							(end 0.381 0.3683)
						)
						(arc
							(start 0.381 -0.3683)
							(mid 0.321484 -0.511984)
							(end 0.1778 -0.5715)
						)
					)
					(width 0)
					(fill yes)
				)
			)
		)
		(pad "G" smd custom
			(at 0.98425 0.9525 180)
			(size 0.1905 0.1905)
			(layers "B.Cu" "B.Mask" "B.Paste")
			(net "DRIVE_A_27_33_ACT")
			(options
				(clearance outline)
				(anchor circle)
			)
			(primitives
				(gr_poly
					(pts
						(arc
							(start -0.1778 -0.5715)
							(mid -0.321484 -0.511984)
							(end -0.381 -0.3683)
						)
						(arc
							(start -0.381 0.3683)
							(mid -0.321484 0.511984)
							(end -0.1778 0.5715)
						)
						(arc
							(start 0.1778 0.5715)
							(mid 0.321484 0.511984)
							(end 0.381 0.3683)
						)
						(arc
							(start 0.381 -0.3683)
							(mid 0.321484 -0.511984)
							(end 0.1778 -0.5715)
						)
					)
					(width 0)
					(fill yes)
				)
			)
		)
		(pad "S" smd custom
			(at -0.98425 0.9525 180)
			(size 0.1905 0.1905)
			(layers "B.Cu" "B.Mask" "B.Paste")
			(net "GND")
			(options
				(clearance outline)
				(anchor circle)
			)
			(primitives
				(gr_poly
					(pts
						(arc
							(start -0.1778 -0.5715)
							(mid -0.321484 -0.511984)
							(end -0.381 -0.3683)
						)
						(arc
							(start -0.381 0.3683)
							(mid -0.321484 0.511984)
							(end -0.1778 0.5715)
						)
						(arc
							(start 0.1778 0.5715)
							(mid 0.321484 0.511984)
							(end 0.381 0.3683)
						)
						(arc
							(start 0.381 -0.3683)
							(mid 0.321484 -0.511984)
							(end 0.1778 -0.5715)
						)
					)
					(width 0)
					(fill yes)
				)
			)
		)
	)
)
